# T6G (Grand Teton) — schematic netlist excerpt (pin names and nets, part order shuffled) for the footprints in the layout excerpt that follows; sources: Cadence DE-HDL packaged netlist, KiCad conversion of 04192023_DAF0TMB3IC0_F0TG_MB_C_brd_V02_OCP.brd

C641  Q_CAP  0.1UF 25V 10% X7R  pkg 0402  page 132 : A = P3V3_AUX ; B = GND
R473  Q_RES  0 5% CHIP  pkg 0402LF  page 29 : A = CLK_ESPI_CPU0_CLK1 ; B = CLK_ESPI_CPU0_R_CLK1

(kicad_pcb
	(version 20260206)
	(generator "pcbnew")
	(generator_version "10.0")
	(general
		(thickness 1.6)
		(legacy_teardrops no)
	)
	(paper "A4")
	(title_block
		(title "04192023_DAF0TMB3IC0_F0TG_MB_C_brd_V02_OCP.brd")
		(comment 1 "Grand Teton / footprints 5716-5717 of 8354")
	)
	(layers
		(0 "F.Cu" signal "TOP")
		(4 "In1.Cu" signal "GND")
		(6 "In2.Cu" signal "IN1")
		(8 "In3.Cu" signal "GND1")
		(10 "In4.Cu" signal "IN2")
		(12 "In5.Cu" signal "GND2")
		(14 "In6.Cu" signal "IN3")
		(16 "In7.Cu" signal "GND3")
		(18 "In8.Cu" signal "VCC")
		(20 "In9.Cu" signal "VCC1")
		(22 "In10.Cu" signal "GND4")
		(24 "In11.Cu" signal "IN4")
		(26 "In12.Cu" signal "GND5")
		(28 "In13.Cu" signal "IN5")
		(30 "In14.Cu" signal "GND6")
		(32 "In15.Cu" signal "IN6")
		(34 "In16.Cu" signal "GND7")
		(2 "B.Cu" signal "BOTTOM")
		(9 "F.Adhes" user "F.Adhesive")
		(11 "B.Adhes" user "B.Adhesive")
		(13 "F.Paste" user "Package Geometry/Pastemask Top")
		(15 "B.Paste" user "Package Geometry/Pastemask Bottom")
		(5 "F.SilkS" user "Ref Des/Silkscreen Top")
		(7 "B.SilkS" user "Ref Des/Silkscreen Bottom")
		(1 "F.Mask" user "Board Geometry/Soldermask Top")
		(3 "B.Mask" user "Board Geometry/Soldermask Bottom")
		(17 "Dwgs.User" user "User.Drawings")
		(19 "Cmts.User" user "User.Comments")
		(21 "Eco1.User" user "User.Eco1")
		(23 "Eco2.User" user "User.Eco2")
		(25 "Edge.Cuts" user "Board Geometry/Outline")
		(27 "Margin" user)
		(31 "F.CrtYd" user "Package Geometry/Place Bound Top")
		(29 "B.CrtYd" user "Package Geometry/Place Bound Bottom")
		(35 "F.Fab" user "Ref Des/Assembly Top")
		(33 "B.Fab" user "Ref Des/Assembly Bottom")
	)
	(footprint ""
		(layer "B.Cu")
		(at 391.585958 -321.179952)
		(property "Reference" "R473"
			(at 0 0 0)
			(layer "B.SilkS")
			(hide yes)
			(effects
				(font
					(size 1.27 1.27)
				)
				(justify mirror)
			)
		)
		(property "Value" ""
			(at 0 0 0)
			(layer "B.Fab")
			(effects
				(font
					(size 1.27 1.27)
				)
				(justify mirror)
			)
		)
		(duplicate_pad_numbers_are_jumpers no)
		(fp_line
			(start -0.7874 -0.4064)
			(end -0.7874 0.4064)
			(stroke
				(width 0.1524)
				(type default)
			)
			(layer "B.SilkS")
		)
		(fp_line
			(start -0.7874 0.4064)
			(end 0.7874 0.4064)
			(stroke
				(width 0.1524)
				(type default)
			)
			(layer "B.SilkS")
		)
		(fp_line
			(start 0.7874 -0.4064)
			(end -0.7874 -0.4064)
			(stroke
				(width 0.1524)
				(type default)
			)
			(layer "B.SilkS")
		)
		(fp_line
			(start 0.7874 0.4064)
			(end 0.7874 -0.4064)
			(stroke
				(width 0.1524)
				(type default)
			)
			(layer "B.SilkS")
		)
		(fp_line
			(start -0.67945 -0.3048)
			(end -0.67945 0.3048)
			(stroke
				(width 0.1)
				(type default)
			)
			(layer "B.Fab")
		)
		(fp_line
			(start -0.67945 0.3048)
			(end -0.120396 0.3048)
			(stroke
				(width 0.1)
				(type default)
			)
			(layer "B.Fab")
		)
		(fp_line
			(start -0.12065 -0.3048)
			(end -0.67945 -0.3048)
			(stroke
				(width 0.1)
				(type default)
			)
			(layer "B.Fab")
		)
		(fp_line
			(start -0.12065 -0.2794)
			(end -0.12065 -0.3048)
			(stroke
				(width 0.1)
				(type default)
			)
			(layer "B.Fab")
		)
		(fp_line
			(start -0.120396 0.2794)
			(end 0.12065 0.2794)
			(stroke
				(width 0.1)
				(type default)
			)
			(layer "B.Fab")
		)
		(fp_line
			(start -0.120396 0.3048)
			(end -0.120396 0.2794)
			(stroke
				(width 0.1)
				(type default)
			)
			(layer "B.Fab")
		)
		(fp_line
			(start 0.12065 -0.305054)
			(end 0.12065 -0.2794)
			(stroke
				(width 0.1)
				(type default)
			)
			(layer "B.Fab")
		)
		(fp_line
			(start 0.12065 -0.2794)
			(end -0.12065 -0.2794)
			(stroke
				(width 0.1)
				(type default)
			)
			(layer "B.Fab")
		)
		(fp_line
			(start 0.12065 0.2794)
			(end 0.12065 0.3048)
			(stroke
				(width 0.1)
				(type default)
			)
			(layer "B.Fab")
		)
		(fp_line
			(start 0.12065 0.3048)
			(end 0.67945 0.3048)
			(stroke
				(width 0.1)
				(type default)
			)
			(layer "B.Fab")
		)
		(fp_line
			(start 0.67945 -0.305054)
			(end 0.12065 -0.305054)
			(stroke
				(width 0.1)
				(type default)
			)
			(layer "B.Fab")
		)
		(fp_line
			(start 0.67945 0.3048)
			(end 0.67945 -0.305054)
			(stroke
				(width 0.1)
				(type default)
			)
			(layer "B.Fab")
		)
		(pad "1" smd circle
			(at 0.40005 0 180)
			(size 0 0)
			(layers "B.Cu" "B.Mask" "B.Paste")
			(net "CLK_ESPI_CPU0_CLK1")
		)
		(pad "2" smd circle
			(at -0.40005 0 180)
			(size 0 0)
			(layers "B.Cu" "B.Mask" "B.Paste")
			(net "CLK_ESPI_CPU0_R_CLK1")
		)
	)
	(footprint ""
		(layer "B.Cu")
		(at 209.441034 -73.168002 180)
		(property "Reference" "C641"
			(at 0 0 0)
			(layer "B.SilkS")
			(hide yes)
			(effects
				(font
					(size 1.27 1.27)
				)
				(justify mirror)
			)
		)
		(property "Value" ""
			(at 0 0 0)
			(layer "B.Fab")
			(effects
				(font
					(size 1.27 1.27)
				)
				(justify mirror)
			)
		)
		(duplicate_pad_numbers_are_jumpers no)
		(fp_line
			(start 0.7874 0.4064)
			(end 0.7874 -0.4064)
			(stroke
				(width 0.1524)
				(type default)
			)
			(layer "B.SilkS")
		)
		(fp_line
			(start 0.7874 -0.4064)
			(end -0.7874 -0.4064)
			(stroke
				(width 0.1524)
				(type default)
			)
			(layer "B.SilkS")
		)
		(fp_line
			(start -0.7874 0.4064)
			(end 0.7874 0.4064)
			(stroke
				(width 0.1524)
				(type default)
			)
			(layer "B.SilkS")
		)
		(fp_line
			(start -0.7874 -0.4064)
			(end -0.7874 0.4064)
			(stroke
				(width 0.1524)
				(type default)
			)
			(layer "B.SilkS")
		)
		(fp_line
			(start 0.67945 0.3048)
			(end 0.67945 -0.305054)
			(stroke
				(width 0.1)
				(type default)
			)
			(layer "B.Fab")
		)
		(fp_line
			(start 0.67945 -0.305054)
			(end 0.12065 -0.305054)
			(stroke
				(width 0.1)
				(type default)
			)
			(layer "B.Fab")
		)
		(fp_line
			(start 0.12065 0.3048)
			(end 0.67945 0.3048)
			(stroke
				(width 0.1)
				(type default)
			)
			(layer "B.Fab")
		)
		(fp_line
			(start 0.12065 0.2794)
			(end 0.12065 0.3048)
			(stroke
				(width 0.1)
				(type default)
			)
			(layer "B.Fab")
		)
		(fp_line
			(start 0.12065 -0.2794)
			(end -0.12065 -0.2794)
			(stroke
				(width 0.1)
				(type default)
			)
			(layer "B.Fab")
		)
		(fp_line
			(start 0.12065 -0.305054)
			(end 0.12065 -0.2794)
			(stroke
				(width 0.1)
				(type default)
			)
			(layer "B.Fab")
		)
		(fp_line
			(start -0.120396 0.3048)
			(end -0.120396 0.2794)
			(stroke
				(width 0.1)
				(type default)
			)
			(layer "B.Fab")
		)
		(fp_line
			(start -0.120396 0.2794)
			(end 0.12065 0.2794)
			(stroke
				(width 0.1)
				(type default)
			)
			(layer "B.Fab")
		)
		(fp_line
			(start -0.12065 -0.2794)
			(end -0.12065 -0.3048)
			(stroke
				(width 0.1)
				(type default)
			)
			(layer "B.Fab")
		)
		(fp_line
			(start -0.12065 -0.3048)
			(end -0.67945 -0.3048)
			(stroke
				(width 0.1)
				(type default)
			)
			(layer "B.Fab")
		)
		(fp_line
			(start -0.67945 0.3048)
			(end -0.120396 0.3048)
			(stroke
				(width 0.1)
				(type default)
			)
			(layer "B.Fab")
		)
		(fp_line
			(start -0.67945 -0.3048)
			(end -0.67945 0.3048)
			(stroke
				(width 0.1)
				(type default)
			)
			(layer "B.Fab")
		)
		(pad "1" smd circle
			(at 0.40005 0)
			(size 0 0)
			(layers "B.Cu" "B.Mask" "B.Paste")
			(net "P3V3_AUX")
		)
		(pad "2" smd circle
			(at -0.40005 0)
			(size 0 0)
			(layers "B.Cu" "B.Mask" "B.Paste")
			(net "GND")
		)
	)
)
